# Thunderbolt GPU Adapter — symbol library table
(sym_lib_table
  (version 7)
)
